# BASEBOARD_FAB2 (Tioga Pass) — schematic netlist excerpt (pin names and nets, part order shuffled) for the footprints in the layout excerpt that follows; sources: Cadence DE-HDL packaged netlist, KiCad conversion of Wiwynn_Tioga_Pass_MB.brd

J4A2  SCONN288_H44441004  SCONN  pkg PIP  page 51
  \12v\(1)  = P12V_NVDIMM_DEF
  VSS(93)  = GND
  DQ(4)  = M_E_DQ<5>
  VSS(92)  = GND
  DQ(0)  = M_E_DQ<1>
  VSS(91)  = GND
  DQS9P  = M_E_DQS_DP<9>
  DQS9N  = M_E_DQS_DN<9>
  VSS(90)  = GND
  DQ(6)  = M_E_DQ<7>
  VSS(89)  = GND
  DQ(2)  = M_E_DQ<3>
  VSS(88)  = GND
  DQ(12)  = M_E_DQ<13>
  VSS(87)  = GND
  DQ(8)  = M_E_DQ<9>
  VSS(86)  = GND
  DQS10P  = M_E_DQS_DP<10>
  DQS10N  = M_E_DQS_DN<10>
  VSS(85)  = GND
  DQ(14)  = M_E_DQ<15>
  VSS(84)  = GND
  DQ(10)  = M_E_DQ<11>
  VSS(83)  = GND
  DQ(20)  = M_E_DQ<21>
  VSS(82)  = GND
  DQ(16)  = M_E_DQ<17>
  VSS(81)  = GND
  DQS11P  = M_E_DQS_DP<11>
  DQS11N  = M_E_DQS_DN<11>
  VSS(80)  = GND
  DQ(22)  = M_E_DQ<23>
  VSS(79)  = GND
  DQ(18)  = M_E_DQ<19>
  VSS(78)  = GND
  DQ(28)  = M_E_DQ<29>
  VSS(77)  = GND
  DQ(24)  = M_E_DQ<25>
  VSS(76)  = GND
  DQS12P  = M_E_DQS_DP<12>
  DQS12N  = M_E_DQS_DN<12>
  VSS(75)  = GND
  DQ(30)  = M_E_DQ<31>
  VSS(74)  = GND
  DQ(26)  = M_E_DQ<27>
  VSS(73)  = GND
  CB(4)  = M_E_ECC<5>
  VSS(72)  = GND
  CB(0)  = M_E_ECC<1>
  VSS(71)  = GND
  DQS17P  = M_E_DQS_DP<17>
  DQS17N  = M_E_DQS_DN<17>
  VSS(70)  = GND
  CB(6)  = M_E_ECC<7>
  VSS(69)  = GND
  CB(2)  = M_E_ECC<3>
  VSS(68)  = GND
  RESET_N  = M_DEF_RST_N
  VDD(25)  = PVDDQ_DEF
  CKE(0)  = M_E_CKE<0>
  VDD(24)  = PVDDQ_DEF
  ACT_N  = M_E_ACT_N
  BG(0)  = M_E_BG<0>
  VDD(23)  = PVDDQ_DEF
  A12  = M_E_MA<12>
  A9  = M_E_MA<9>
  VDD(22)  = PVDDQ_DEF
  A8  = M_E_MA<8>
  A6  = M_E_MA<6>
  VDD(21)  = PVDDQ_DEF
  A3  = M_E_MA<3>
  A1  = M_E_MA<1>
  VDD(20)  = PVDDQ_DEF
  CK0P  = M_E_CLK_DP<0>
  CK0N  = M_E_CLK_DN<0>
  VDD(19)  = PVDDQ_DEF
  VTT(1)  = PVTT_DEF
  EVENT_N  = FM_DIMM_EVENT_COD_N
  A0  = M_E_MA<0>
  VDD(18)  = PVDDQ_DEF
  BA(0)  = M_E_BA<0>
  A16_RAS_N  = M_E_MA<16>
  VDD(17)  = PVDDQ_DEF
  S0_N  = M_E_CS_N<0>
  VDD(16)  = PVDDQ_DEF
  A15_CAS_N  = M_E_MA<15>
  ODT(0)  = M_E_ODT<0>
  VDD(15)  = PVDDQ_DEF
  S1_N  = M_E_CS_N<1>
  VDD(14)  = PVDDQ_DEF
  ODT(1)  = M_E_ODT<1>
  VDD(13)  = PVDDQ_DEF
  S2_N_C(0)  = M_E_CS_N<2>
  VSS(67)  = GND
  DQ(36)  = M_E_DQ<37>
  VSS(66)  = GND
  DQ(32)  = M_E_DQ<33>
  VSS(65)  = GND
  DQS13P  = M_E_DQS_DP<13>
  DQS13N  = M_E_DQS_DN<13>
  VSS(64)  = GND
  DQ(38)  = M_E_DQ<39>
  VSS(63)  = GND
  DQ(34)  = M_E_DQ<35>
  VSS(62)  = GND
  DQ(44)  = M_E_DQ<45>
  VSS(61)  = GND
  DQ(40)  = M_E_DQ<41>
  VSS(60)  = GND
  DQS14P  = M_E_DQS_DP<14>
  DQS14N  = M_E_DQS_DN<14>
  VSS(59)  = GND
  DQ(46)  = M_E_DQ<47>
  VSS(58)  = GND
  DQ(42)  = M_E_DQ<43>
  VSS(57)  = GND
  DQ(52)  = M_E_DQ<53>
  VSS(56)  = GND
  DQ(48)  = M_E_DQ<49>
  VSS(55)  = GND
  DQS15P  = M_E_DQS_DP<15>
  DQS15N  = M_E_DQS_DN<15>
  VSS(54)  = GND
  DQ(54)  = M_E_DQ<55>
  VSS(53)  = GND
  DQ(50)  = M_E_DQ<51>
  VSS(52)  = GND
  DQ(60)  = M_E_DQ<61>
  VSS(51)  = GND
  DQ(56)  = M_E_DQ<57>
  VSS(50)  = GND
  DQS16P  = M_E_DQS_DP<16>
  DQS16N  = M_E_DQS_DN<16>
  VSS(49)  = GND
  DQ(62)  = M_E_DQ<63>
  VSS(48)  = GND
  DQ(58)  = M_E_DQ<59>
  VSS(47)  = GND
  SA(0)  = GND
  SA(1)  = PVPP_DEF
  SCL  = SMB_DDR_DEF_VPP_SCL
  VPP(4)  = PVPP_DEF
  VPP(3)  = PVPP_DEF
  RFU(2)  = TP_CH_E_DIMM_E0_RFU_2
  \12v\(0)  = P12V_NVDIMM_DEF
  VREFCA  = M_E_VREF
  VSS(46)  = GND
  DQ(5)  = M_E_DQ<4>
  VSS(45)  = GND
  DQ(1)  = M_E_DQ<0>
  VSS(44)  = GND
  DQS0N  = M_E_DQS_DN<0>
  DQS0P  = M_E_DQS_DP<0>
  VSS(43)  = GND
  DQ(7)  = M_E_DQ<6>
  VSS(42)  = GND
  DQ(3)  = M_E_DQ<2>
  VSS(41)  = GND
  DQ(13)  = M_E_DQ<12>
  VSS(40)  = GND
  DQ(9)  = M_E_DQ<8>
  VSS(39)  = GND
  DQS1N  = M_E_DQS_DN<1>
  DQS1P  = M_E_DQS_DP<1>
  VSS(38)  = GND
  DQ(15)  = M_E_DQ<14>
  VSS(37)  = GND
  DQ(11)  = M_E_DQ<10>
  VSS(36)  = GND
  DQ(21)  = M_E_DQ<20>
  VSS(35)  = GND
  DQ(17)  = M_E_DQ<16>
  VSS(34)  = GND
  DQS2N  = M_E_DQS_DN<2>
  DQS2P  = M_E_DQS_DP<2>
  VSS(33)  = GND
  DQ(23)  = M_E_DQ<22>
  VSS(32)  = GND
  DQ(19)  = M_E_DQ<18>
  VSS(31)  = GND
  DQ(29)  = M_E_DQ<28>
  VSS(30)  = GND
  DQ(25)  = M_E_DQ<24>
  VSS(29)  = GND
  DQS3N  = M_E_DQS_DN<3>
  DQS3P  = M_E_DQS_DP<3>
  VSS(28)  = GND
  DQ(31)  = M_E_DQ<30>
  VSS(27)  = GND
  DQ(27)  = M_E_DQ<26>
  VSS(26)  = GND
  CB(5)  = M_E_ECC<4>
  VSS(25)  = GND
  CB(1)  = M_E_ECC<0>
  VSS(24)  = GND
  DQS8N  = M_E_DQS_DN<8>
  DQS8P  = M_E_DQS_DP<8>
  VSS(23)  = GND
  CB(7)  = M_E_ECC<6>
  VSS(22)  = GND
  CB(3)  = M_E_ECC<2>
  VSS(21)  = GND
  CKE(1)  = M_E_CKE<1>
  VDD(12)  = PVDDQ_DEF
  RFU(0)  = TP_CH_E_DIMM_E0_RFU_0
  VDD(11)  = PVDDQ_DEF
  BG(1)  = M_E_BG<1>
  ALERT_N  = M_E_ALERT_N
  VDD(10)  = PVDDQ_DEF
  A11  = M_E_MA<11>
  A7  = M_E_MA<7>
  VDD(9)  = PVDDQ_DEF
  A5  = M_E_MA<5>
  A4  = M_E_MA<4>
  VDD(8)  = PVDDQ_DEF
  A2  = M_E_MA<2>
  VDD(7)  = PVDDQ_DEF
  CK1P  = M_E_CLK_DP<1>
  CK1N  = M_E_CLK_DN<1>
  VDD(6)  = PVDDQ_DEF
  VTT(0)  = PVTT_DEF
  PAR  = M_E_PAR
  VDD(5)  = PVDDQ_DEF
  BA(1)  = M_E_BA<1>
  A10  = M_E_MA<10>
  VDD(4)  = PVDDQ_DEF
  RFU(1)  = TP_CH_E_DIMM_E0_RFU_1
  A14_WE_N  = M_E_MA<14>
  VDD(3)  = PVDDQ_DEF
  SAVE_N_NC  = FM_ADR_COMPLETE_DEF_N
  VDD(2)  = PVDDQ_DEF
  A13  = M_E_MA<13>
  VDD(1)  = PVDDQ_DEF
  A17  = M_E_MA<17>
  C(2)  = M_E_C<2>
  VDD(0)  = PVDDQ_DEF
  S3_N_C(1)  = M_E_CS_N<3>
  SA(2)  = GND
  VSS(20)  = GND
  DQ(37)  = M_E_DQ<36>
  VSS(19)  = GND
  DQ(33)  = M_E_DQ<32>
  VSS(18)  = GND
  DQS4N  = M_E_DQS_DN<4>
  DQS4P  = M_E_DQS_DP<4>
  VSS(17)  = GND
  DQ(39)  = M_E_DQ<38>
  VSS(16)  = GND
  DQ(35)  = M_E_DQ<34>
  VSS(15)  = GND
  DQ(45)  = M_E_DQ<44>
  VSS(14)  = GND
  DQ(41)  = M_E_DQ<40>
  VSS(13)  = GND
  DQS5N  = M_E_DQS_DN<5>
  DQS5P  = M_E_DQS_DP<5>
  VSS(12)  = GND
  DQ(47)  = M_E_DQ<46>
  VSS(11)  = GND
  DQ(43)  = M_E_DQ<42>
  VSS(10)  = GND
  DQ(53)  = M_E_DQ<52>
  VSS(9)  = GND
  DQ(49)  = M_E_DQ<48>
  VSS(8)  = GND
  DQS6N  = M_E_DQS_DN<6>
  DQS6P  = M_E_DQS_DP<6>
  VSS(7)  = GND
  DQ(55)  = M_E_DQ<54>
  VSS(6)  = GND
  DQ(51)  = M_E_DQ<50>
  VSS(5)  = GND
  DQ(61)  = M_E_DQ<60>
  VSS(4)  = GND
  DQ(57)  = M_E_DQ<56>
  VSS(3)  = GND
  DQS7N  = M_E_DQS_DN<7>
  DQS7P  = M_E_DQS_DP<7>
  VSS(2)  = GND
  DQ(63)  = M_E_DQ<62>
  VSS(1)  = GND
  DQ(59)  = M_E_DQ<58>
  VSS(0)  = GND
  VDDSPD  = PVPP_DEF
  SDA  = SMB_DDR_DEF_VPP_SDA
  VPP(1)  = PVPP_DEF
  VPP(0)  = PVPP_DEF
  VPP(2)  = PVPP_DEF

(kicad_pcb
	(version 20260206)
	(generator "pcbnew")
	(generator_version "10.0")
	(general
		(thickness 1.6)
		(legacy_teardrops no)
	)
	(paper "A4")
	(title_block
		(title "Wiwynn_Tioga_Pass_MB.brd")
		(comment 1 "Tioga Pass / footprint 2096 of 4770 (J4A2), pads 102-152 of 291")
	)
	(layers
		(0 "F.Cu" signal "TOP")
		(4 "In1.Cu" signal "L2GND")
		(6 "In2.Cu" signal "L3")
		(8 "In3.Cu" signal "L4GND")
		(10 "In4.Cu" signal "L5")
		(12 "In5.Cu" signal "L6GND")
		(14 "In6.Cu" signal "L7VCC")
		(16 "In7.Cu" signal "L8VCC")
		(18 "In8.Cu" signal "L9GND")
		(20 "In9.Cu" signal "L10")
		(22 "In10.Cu" signal "L11GND")
		(24 "In11.Cu" signal "L12")
		(26 "In12.Cu" signal "L13GND")
		(2 "B.Cu" signal "BOTTOM")
		(9 "F.Adhes" user "F.Adhesive")
		(11 "B.Adhes" user "B.Adhesive")
		(13 "F.Paste" user "Package Geometry/Pastemask Top")
		(15 "B.Paste" user "Package Geometry/Pastemask Bottom")
		(5 "F.SilkS" user "Ref Des/Silkscreen Top")
		(7 "B.SilkS" user "Ref Des/Silkscreen Bottom")
		(1 "F.Mask" user "Board Geometry/Soldermask Top")
		(3 "B.Mask" user "Board Geometry/Soldermask Bottom")
		(17 "Dwgs.User" user "User.Drawings")
		(19 "Cmts.User" user "User.Comments")
		(21 "Eco1.User" user "User.Eco1")
		(23 "Eco2.User" user "User.Eco2")
		(25 "Edge.Cuts" user "Board Geometry/Outline")
		(27 "Margin" user)
		(31 "F.CrtYd" user "Package Geometry/Place Bound Top")
		(29 "B.CrtYd" user "Package Geometry/Place Bound Bottom")
		(35 "F.Fab" user "Ref Des/Assembly Top")
		(33 "B.Fab" user "Ref Des/Assembly Bottom")
	)
	(footprint ""
		(layer "F.Cu")
		(at 194.700398 -142.6718 90)
		(property "Reference" "J4A2"
			(at -2.369312 42.66311 0)
			(unlocked yes)
			(layer "F.SilkS")
			(effects
				(font
					(size 0.7874 0.5842)
					(thickness 0.1524)
				)
				(justify left)
			)
		)
		(property "Value" ""
			(at 0 0 90)
			(layer "F.Fab")
			(effects
				(font
					(size 1.27 1.27)
				)
			)
		)
		(duplicate_pad_numbers_are_jumpers no)
		(pad "99" smd rect
			(at 0 88.399874 90)
			(size 1.8034 0.508)
			(layers "F.Cu" "F.Mask" "F.Paste")
			(net "M_E_DQS_DP<13>")
		)
		(pad "100" smd rect
			(at 0 89.250012 90)
			(size 1.8034 0.508)
			(layers "F.Cu" "F.Mask" "F.Paste")
			(net "M_E_DQS_DN<13>")
		)
		(pad "101" smd rect
			(at 0 90.099896 90)
			(size 1.8034 0.508)
			(layers "F.Cu" "F.Mask" "F.Paste")
			(net "GND")
		)
		(pad "102" smd rect
			(at 0 90.950034 90)
			(size 1.8034 0.508)
			(layers "F.Cu" "F.Mask" "F.Paste")
			(net "M_E_DQ<39>")
		)
		(pad "103" smd rect
			(at 0 91.799918 90)
			(size 1.8034 0.508)
			(layers "F.Cu" "F.Mask" "F.Paste")
			(net "GND")
		)
		(pad "104" smd rect
			(at 0 92.650056 90)
			(size 1.8034 0.508)
			(layers "F.Cu" "F.Mask" "F.Paste")
			(net "M_E_DQ<35>")
		)
		(pad "105" smd rect
			(at 0 93.49994 90)
			(size 1.8034 0.508)
			(layers "F.Cu" "F.Mask" "F.Paste")
			(net "GND")
		)
		(pad "106" smd rect
			(at 0 94.350078 90)
			(size 1.8034 0.508)
			(layers "F.Cu" "F.Mask" "F.Paste")
			(net "M_E_DQ<45>")
		)
		(pad "107" smd rect
			(at 0 95.199962 90)
			(size 1.8034 0.508)
			(layers "F.Cu" "F.Mask" "F.Paste")
			(net "GND")
		)
		(pad "108" smd rect
			(at 0 96.0501 90)
			(size 1.8034 0.508)
			(layers "F.Cu" "F.Mask" "F.Paste")
			(net "M_E_DQ<41>")
		)
		(pad "109" smd rect
			(at 0 96.899984 90)
			(size 1.8034 0.508)
			(layers "F.Cu" "F.Mask" "F.Paste")
			(net "GND")
		)
		(pad "110" smd rect
			(at 0 97.750122 90)
			(size 1.8034 0.508)
			(layers "F.Cu" "F.Mask" "F.Paste")
			(net "M_E_DQS_DP<14>")
		)
		(pad "111" smd rect
			(at 0 98.600006 90)
			(size 1.8034 0.508)
			(layers "F.Cu" "F.Mask" "F.Paste")
			(net "M_E_DQS_DN<14>")
		)
		(pad "112" smd rect
			(at 0 99.44989 90)
			(size 1.8034 0.508)
			(layers "F.Cu" "F.Mask" "F.Paste")
			(net "GND")
		)
		(pad "113" smd rect
			(at 0 100.300028 90)
			(size 1.8034 0.508)
			(layers "F.Cu" "F.Mask" "F.Paste")
			(net "M_E_DQ<47>")
		)
		(pad "114" smd rect
			(at 0 101.149912 90)
			(size 1.8034 0.508)
			(layers "F.Cu" "F.Mask" "F.Paste")
			(net "GND")
		)
		(pad "115" smd rect
			(at 0 102.00005 90)
			(size 1.8034 0.508)
			(layers "F.Cu" "F.Mask" "F.Paste")
			(net "M_E_DQ<43>")
		)
		(pad "116" smd rect
			(at 0 102.849934 90)
			(size 1.8034 0.508)
			(layers "F.Cu" "F.Mask" "F.Paste")
			(net "GND")
		)
		(pad "117" smd rect
			(at 0 103.700072 90)
			(size 1.8034 0.508)
			(layers "F.Cu" "F.Mask" "F.Paste")
			(net "M_E_DQ<53>")
		)
		(pad "118" smd rect
			(at 0 104.549956 90)
			(size 1.8034 0.508)
			(layers "F.Cu" "F.Mask" "F.Paste")
			(net "GND")
		)
		(pad "119" smd rect
			(at 0 105.400094 90)
			(size 1.8034 0.508)
			(layers "F.Cu" "F.Mask" "F.Paste")
			(net "M_E_DQ<49>")
		)
		(pad "120" smd rect
			(at 0 106.249978 90)
			(size 1.8034 0.508)
			(layers "F.Cu" "F.Mask" "F.Paste")
			(net "GND")
		)
		(pad "121" smd rect
			(at 0 107.100116 90)
			(size 1.8034 0.508)
			(layers "F.Cu" "F.Mask" "F.Paste")
			(net "M_E_DQS_DP<15>")
		)
		(pad "122" smd rect
			(at 0 107.95 90)
			(size 1.8034 0.508)
			(layers "F.Cu" "F.Mask" "F.Paste")
			(net "M_E_DQS_DN<15>")
		)
		(pad "123" smd rect
			(at 0 108.799884 90)
			(size 1.8034 0.508)
			(layers "F.Cu" "F.Mask" "F.Paste")
			(net "GND")
		)
		(pad "124" smd rect
			(at 0 109.650022 90)
			(size 1.8034 0.508)
			(layers "F.Cu" "F.Mask" "F.Paste")
			(net "M_E_DQ<55>")
		)
		(pad "125" smd rect
			(at 0 110.499906 90)
			(size 1.8034 0.508)
			(layers "F.Cu" "F.Mask" "F.Paste")
			(net "GND")
		)
		(pad "126" smd rect
			(at 0 111.350044 90)
			(size 1.8034 0.508)
			(layers "F.Cu" "F.Mask" "F.Paste")
			(net "M_E_DQ<51>")
		)
		(pad "127" smd rect
			(at 0 112.199928 90)
			(size 1.8034 0.508)
			(layers "F.Cu" "F.Mask" "F.Paste")
			(net "GND")
		)
		(pad "128" smd rect
			(at 0 113.050066 90)
			(size 1.8034 0.508)
			(layers "F.Cu" "F.Mask" "F.Paste")
			(net "M_E_DQ<61>")
		)
		(pad "129" smd rect
			(at 0 113.89995 90)
			(size 1.8034 0.508)
			(layers "F.Cu" "F.Mask" "F.Paste")
			(net "GND")
		)
		(pad "130" smd rect
			(at 0 114.750088 90)
			(size 1.8034 0.508)
			(layers "F.Cu" "F.Mask" "F.Paste")
			(net "M_E_DQ<57>")
		)
		(pad "131" smd rect
			(at 0 115.599972 90)
			(size 1.8034 0.508)
			(layers "F.Cu" "F.Mask" "F.Paste")
			(net "GND")
		)
		(pad "132" smd rect
			(at 0 116.45011 90)
			(size 1.8034 0.508)
			(layers "F.Cu" "F.Mask" "F.Paste")
			(net "M_E_DQS_DP<16>")
		)
		(pad "133" smd rect
			(at 0 117.299994 90)
			(size 1.8034 0.508)
			(layers "F.Cu" "F.Mask" "F.Paste")
			(net "M_E_DQS_DN<16>")
		)
		(pad "134" smd rect
			(at 0 118.149878 90)
			(size 1.8034 0.508)
			(layers "F.Cu" "F.Mask" "F.Paste")
			(net "GND")
		)
		(pad "135" smd rect
			(at 0 119.000016 90)
			(size 1.8034 0.508)
			(layers "F.Cu" "F.Mask" "F.Paste")
			(net "M_E_DQ<63>")
		)
		(pad "136" smd rect
			(at 0 119.8499 90)
			(size 1.8034 0.508)
			(layers "F.Cu" "F.Mask" "F.Paste")
			(net "GND")
		)
		(pad "137" smd rect
			(at 0 120.700038 90)
			(size 1.8034 0.508)
			(layers "F.Cu" "F.Mask" "F.Paste")
			(net "M_E_DQ<59>")
		)
		(pad "138" smd rect
			(at 0 121.549922 90)
			(size 1.8034 0.508)
			(layers "F.Cu" "F.Mask" "F.Paste")
			(net "GND")
		)
		(pad "139" smd rect
			(at 0 122.40006 90)
			(size 1.8034 0.508)
			(layers "F.Cu" "F.Mask" "F.Paste")
			(net "GND")
		)
		(pad "140" smd rect
			(at 0 123.249944 90)
			(size 1.8034 0.508)
			(layers "F.Cu" "F.Mask" "F.Paste")
			(net "PVPP_DEF")
		)
		(pad "141" smd rect
			(at 0 124.100082 90)
			(size 1.8034 0.508)
			(layers "F.Cu" "F.Mask" "F.Paste")
			(net "SMB_DDR_DEF_VPP_SCL")
		)
		(pad "142" smd rect
			(at 0 124.949966 90)
			(size 1.8034 0.508)
			(layers "F.Cu" "F.Mask" "F.Paste")
			(net "PVPP_DEF")
		)
		(pad "143" smd rect
			(at 0 125.800104 90)
			(size 1.8034 0.508)
			(layers "F.Cu" "F.Mask" "F.Paste")
			(net "PVPP_DEF")
		)
		(pad "144" smd rect
			(at 0 126.649988 90)
			(size 1.8034 0.508)
			(layers "F.Cu" "F.Mask" "F.Paste")
			(net "TP_CH_E_DIMM_E0_RFU_2")
		)
		(pad "145" smd rect
			(at 4.59994 0 90)
			(size 1.8034 0.508)
			(layers "F.Cu" "F.Mask" "F.Paste")
			(net "P12V_NVDIMM_DEF")
		)
		(pad "146" smd rect
			(at 4.59994 0.849884 90)
			(size 1.8034 0.508)
			(layers "F.Cu" "F.Mask" "F.Paste")
			(net "M_E_VREF")
		)
		(pad "147" smd rect
			(at 4.59994 1.700022 90)
			(size 1.8034 0.508)
			(layers "F.Cu" "F.Mask" "F.Paste")
			(net "GND")
		)
		(pad "148" smd rect
			(at 4.59994 2.549906 90)
			(size 1.8034 0.508)
			(layers "F.Cu" "F.Mask" "F.Paste")
			(net "M_E_DQ<4>")
		)
		(pad "149" smd rect
			(at 4.59994 3.400044 90)
			(size 1.8034 0.508)
			(layers "F.Cu" "F.Mask" "F.Paste")
			(net "GND")
		)
	)
)
